# T6G (Grand Teton) — schematic netlist excerpt (pin names and nets, part order shuffled) for the footprints in the layout excerpt that follows; sources: Cadence DE-HDL packaged netlist, KiCad conversion of 04192023_DAF0TMB3IC0_F0TG_MB_C_brd_V02_OCP.brd

C4  Q_CAP  0.1UF 25V 10% X7R  pkg 0402  page 124 : A = GPU_3V3IO_RSVD1_ISO ; B = GND
R4185  Q_RES  1K 1% CHIP  pkg 0402LF  page 235 : A = U273_3_ADD2 ; B = GND

(kicad_pcb
	(version 20260206)
	(generator "pcbnew")
	(generator_version "10.0")
	(general
		(thickness 1.6)
		(legacy_teardrops no)
	)
	(paper "A4")
	(title_block
		(title "04192023_DAF0TMB3IC0_F0TG_MB_C_brd_V02_OCP.brd")
		(comment 1 "Grand Teton / footprints 1231-1232 of 8354")
	)
	(layers
		(0 "F.Cu" signal "TOP")
		(4 "In1.Cu" signal "GND")
		(6 "In2.Cu" signal "IN1")
		(8 "In3.Cu" signal "GND1")
		(10 "In4.Cu" signal "IN2")
		(12 "In5.Cu" signal "GND2")
		(14 "In6.Cu" signal "IN3")
		(16 "In7.Cu" signal "GND3")
		(18 "In8.Cu" signal "VCC")
		(20 "In9.Cu" signal "VCC1")
		(22 "In10.Cu" signal "GND4")
		(24 "In11.Cu" signal "IN4")
		(26 "In12.Cu" signal "GND5")
		(28 "In13.Cu" signal "IN5")
		(30 "In14.Cu" signal "GND6")
		(32 "In15.Cu" signal "IN6")
		(34 "In16.Cu" signal "GND7")
		(2 "B.Cu" signal "BOTTOM")
		(9 "F.Adhes" user "F.Adhesive")
		(11 "B.Adhes" user "B.Adhesive")
		(13 "F.Paste" user "Package Geometry/Pastemask Top")
		(15 "B.Paste" user "Package Geometry/Pastemask Bottom")
		(5 "F.SilkS" user "Ref Des/Silkscreen Top")
		(7 "B.SilkS" user "Ref Des/Silkscreen Bottom")
		(1 "F.Mask" user "Board Geometry/Soldermask Top")
		(3 "B.Mask" user "Board Geometry/Soldermask Bottom")
		(17 "Dwgs.User" user "User.Drawings")
		(19 "Cmts.User" user "User.Comments")
		(21 "Eco1.User" user "User.Eco1")
		(23 "Eco2.User" user "User.Eco2")
		(25 "Edge.Cuts" user "Board Geometry/Outline")
		(27 "Margin" user)
		(31 "F.CrtYd" user "Package Geometry/Place Bound Top")
		(29 "B.CrtYd" user "Package Geometry/Place Bound Bottom")
		(35 "F.Fab" user "Ref Des/Assembly Top")
		(33 "B.Fab" user "Ref Des/Assembly Bottom")
	)
	(footprint ""
		(layer "F.Cu")
		(at 420.246302 -434.386736 -90)
		(property "Reference" "C4"
			(at 0 0 270)
			(layer "F.SilkS")
			(hide yes)
			(effects
				(font
					(size 1.27 1.27)
				)
			)
		)
		(property "Value" ""
			(at 0 0 270)
			(layer "F.Fab")
			(effects
				(font
					(size 1.27 1.27)
				)
			)
		)
		(duplicate_pad_numbers_are_jumpers no)
		(fp_line
			(start -0.7874 0.4064)
			(end -0.7874 -0.4064)
			(stroke
				(width 0.1524)
				(type default)
			)
			(layer "F.SilkS")
		)
		(fp_line
			(start 0.7874 0.4064)
			(end -0.7874 0.4064)
			(stroke
				(width 0.1524)
				(type default)
			)
			(layer "F.SilkS")
		)
		(fp_line
			(start -0.7874 -0.4064)
			(end 0.7874 -0.4064)
			(stroke
				(width 0.1524)
				(type default)
			)
			(layer "F.SilkS")
		)
		(fp_line
			(start 0.7874 -0.4064)
			(end 0.7874 0.4064)
			(stroke
				(width 0.1524)
				(type default)
			)
			(layer "F.SilkS")
		)
		(fp_line
			(start -0.67945 0.3048)
			(end -0.67945 -0.305054)
			(stroke
				(width 0.1)
				(type default)
			)
			(layer "F.Fab")
		)
		(fp_line
			(start -0.12065 0.3048)
			(end -0.67945 0.3048)
			(stroke
				(width 0.1)
				(type default)
			)
			(layer "F.Fab")
		)
		(fp_line
			(start 0.120396 0.3048)
			(end 0.120396 0.2794)
			(stroke
				(width 0.1)
				(type default)
			)
			(layer "F.Fab")
		)
		(fp_line
			(start 0.67945 0.3048)
			(end 0.120396 0.3048)
			(stroke
				(width 0.1)
				(type default)
			)
			(layer "F.Fab")
		)
		(fp_line
			(start -0.12065 0.2794)
			(end -0.12065 0.3048)
			(stroke
				(width 0.1)
				(type default)
			)
			(layer "F.Fab")
		)
		(fp_line
			(start 0.120396 0.2794)
			(end -0.12065 0.2794)
			(stroke
				(width 0.1)
				(type default)
			)
			(layer "F.Fab")
		)
		(fp_line
			(start -0.12065 -0.2794)
			(end 0.12065 -0.2794)
			(stroke
				(width 0.1)
				(type default)
			)
			(layer "F.Fab")
		)
		(fp_line
			(start 0.12065 -0.2794)
			(end 0.12065 -0.3048)
			(stroke
				(width 0.1)
				(type default)
			)
			(layer "F.Fab")
		)
		(fp_line
			(start 0.12065 -0.3048)
			(end 0.67945 -0.3048)
			(stroke
				(width 0.1)
				(type default)
			)
			(layer "F.Fab")
		)
		(fp_line
			(start 0.67945 -0.3048)
			(end 0.67945 0.3048)
			(stroke
				(width 0.1)
				(type default)
			)
			(layer "F.Fab")
		)
		(fp_line
			(start -0.67945 -0.305054)
			(end -0.12065 -0.305054)
			(stroke
				(width 0.1)
				(type default)
			)
			(layer "F.Fab")
		)
		(fp_line
			(start -0.12065 -0.305054)
			(end -0.12065 -0.2794)
			(stroke
				(width 0.1)
				(type default)
			)
			(layer "F.Fab")
		)
		(pad "1" smd circle
			(at -0.40005 0 270)
			(size 0 0)
			(layers "F.Cu" "F.Mask" "F.Paste")
			(net "GPU_3V3IO_RSVD1_ISO")
		)
		(pad "2" smd circle
			(at 0.40005 0 270)
			(size 0 0)
			(layers "F.Cu" "F.Mask" "F.Paste")
			(net "GND")
		)
	)
	(footprint ""
		(layer "F.Cu")
		(at 120.340882 -14.00429)
		(property "Reference" "R4185"
			(at 0 0 0)
			(layer "F.SilkS")
			(hide yes)
			(effects
				(font
					(size 1.27 1.27)
				)
			)
		)
		(property "Value" ""
			(at 0 0 0)
			(layer "F.Fab")
			(effects
				(font
					(size 1.27 1.27)
				)
			)
		)
		(duplicate_pad_numbers_are_jumpers no)
		(fp_line
			(start -0.7874 -0.4064)
			(end 0.7874 -0.4064)
			(stroke
				(width 0.1524)
				(type default)
			)
			(layer "F.SilkS")
		)
		(fp_line
			(start -0.7874 0.4064)
			(end -0.7874 -0.4064)
			(stroke
				(width 0.1524)
				(type default)
			)
			(layer "F.SilkS")
		)
		(fp_line
			(start 0.7874 -0.4064)
			(end 0.7874 0.4064)
			(stroke
				(width 0.1524)
				(type default)
			)
			(layer "F.SilkS")
		)
		(fp_line
			(start 0.7874 0.4064)
			(end -0.7874 0.4064)
			(stroke
				(width 0.1524)
				(type default)
			)
			(layer "F.SilkS")
		)
		(fp_line
			(start -0.67945 -0.305054)
			(end -0.12065 -0.305054)
			(stroke
				(width 0.1)
				(type default)
			)
			(layer "F.Fab")
		)
		(fp_line
			(start -0.67945 0.3048)
			(end -0.67945 -0.305054)
			(stroke
				(width 0.1)
				(type default)
			)
			(layer "F.Fab")
		)
		(fp_line
			(start -0.12065 -0.305054)
			(end -0.12065 -0.2794)
			(stroke
				(width 0.1)
				(type default)
			)
			(layer "F.Fab")
		)
		(fp_line
			(start -0.12065 -0.2794)
			(end 0.12065 -0.2794)
			(stroke
				(width 0.1)
				(type default)
			)
			(layer "F.Fab")
		)
		(fp_line
			(start -0.12065 0.2794)
			(end -0.12065 0.3048)
			(stroke
				(width 0.1)
				(type default)
			)
			(layer "F.Fab")
		)
		(fp_line
			(start -0.12065 0.3048)
			(end -0.67945 0.3048)
			(stroke
				(width 0.1)
				(type default)
			)
			(layer "F.Fab")
		)
		(fp_line
			(start 0.120396 0.2794)
			(end -0.12065 0.2794)
			(stroke
				(width 0.1)
				(type default)
			)
			(layer "F.Fab")
		)
		(fp_line
			(start 0.120396 0.3048)
			(end 0.120396 0.2794)
			(stroke
				(width 0.1)
				(type default)
			)
			(layer "F.Fab")
		)
		(fp_line
			(start 0.12065 -0.3048)
			(end 0.67945 -0.3048)
			(stroke
				(width 0.1)
				(type default)
			)
			(layer "F.Fab")
		)
		(fp_line
			(start 0.12065 -0.2794)
			(end 0.12065 -0.3048)
			(stroke
				(width 0.1)
				(type default)
			)
			(layer "F.Fab")
		)
		(fp_line
			(start 0.67945 -0.3048)
			(end 0.67945 0.3048)
			(stroke
				(width 0.1)
				(type default)
			)
			(layer "F.Fab")
		)
		(fp_line
			(start 0.67945 0.3048)
			(end 0.120396 0.3048)
			(stroke
				(width 0.1)
				(type default)
			)
			(layer "F.Fab")
		)
		(pad "1" smd circle
			(at -0.40005 0)
			(size 0 0)
			(layers "F.Cu" "F.Mask" "F.Paste")
			(net "U273_3_ADD2")
		)
		(pad "2" smd circle
			(at 0.40005 0)
			(size 0 0)
			(layers "F.Cu" "F.Mask" "F.Paste")
			(net "GND")
		)
	)
)
